# T6G (Grand Teton) — schematic netlist excerpt (pin names and nets, part order shuffled) for the footprints in the layout excerpt that follows; sources: Cadence DE-HDL packaged netlist, KiCad conversion of 04192023_DAF0TMB3IC0_F0TG_MB_C_brd_V02_OCP.brd

C5024  Q_CAP  1000PF 50V 5% X7R  pkg 0402  page 55 : A = RST_CPU1_RSMRST_N ; B = GND
R6151  Q_RES  1K 1% CHIP  pkg 0402LF  page 84 : A = FAB_BMC_REV_ID0 ; B = GND

(kicad_pcb
	(version 20260206)
	(generator "pcbnew")
	(generator_version "10.0")
	(general
		(thickness 1.6)
		(legacy_teardrops no)
	)
	(paper "A4")
	(title_block
		(title "04192023_DAF0TMB3IC0_F0TG_MB_C_brd_V02_OCP.brd")
		(comment 1 "Grand Teton / footprints 4712-4713 of 8354")
	)
	(layers
		(0 "F.Cu" signal "TOP")
		(4 "In1.Cu" signal "GND")
		(6 "In2.Cu" signal "IN1")
		(8 "In3.Cu" signal "GND1")
		(10 "In4.Cu" signal "IN2")
		(12 "In5.Cu" signal "GND2")
		(14 "In6.Cu" signal "IN3")
		(16 "In7.Cu" signal "GND3")
		(18 "In8.Cu" signal "VCC")
		(20 "In9.Cu" signal "VCC1")
		(22 "In10.Cu" signal "GND4")
		(24 "In11.Cu" signal "IN4")
		(26 "In12.Cu" signal "GND5")
		(28 "In13.Cu" signal "IN5")
		(30 "In14.Cu" signal "GND6")
		(32 "In15.Cu" signal "IN6")
		(34 "In16.Cu" signal "GND7")
		(2 "B.Cu" signal "BOTTOM")
		(9 "F.Adhes" user "F.Adhesive")
		(11 "B.Adhes" user "B.Adhesive")
		(13 "F.Paste" user "Package Geometry/Pastemask Top")
		(15 "B.Paste" user "Package Geometry/Pastemask Bottom")
		(5 "F.SilkS" user "Ref Des/Silkscreen Top")
		(7 "B.SilkS" user "Ref Des/Silkscreen Bottom")
		(1 "F.Mask" user "Board Geometry/Soldermask Top")
		(3 "B.Mask" user "Board Geometry/Soldermask Bottom")
		(17 "Dwgs.User" user "User.Drawings")
		(19 "Cmts.User" user "User.Comments")
		(21 "Eco1.User" user "User.Eco1")
		(23 "Eco2.User" user "User.Eco2")
		(25 "Edge.Cuts" user "Board Geometry/Outline")
		(27 "Margin" user)
		(31 "F.CrtYd" user "Package Geometry/Place Bound Top")
		(29 "B.CrtYd" user "Package Geometry/Place Bound Bottom")
		(35 "F.Fab" user "Ref Des/Assembly Top")
		(33 "B.Fab" user "Ref Des/Assembly Bottom")
	)
	(footprint ""
		(layer "F.Cu")
		(at 152.849834 -321.715892)
		(property "Reference" "C5024"
			(at 0 0 0)
			(layer "F.SilkS")
			(hide yes)
			(effects
				(font
					(size 1.27 1.27)
				)
			)
		)
		(property "Value" ""
			(at 0 0 0)
			(layer "F.Fab")
			(effects
				(font
					(size 1.27 1.27)
				)
			)
		)
		(duplicate_pad_numbers_are_jumpers no)
		(fp_line
			(start -0.7874 -0.4064)
			(end 0.7874 -0.4064)
			(stroke
				(width 0.1524)
				(type default)
			)
			(layer "F.SilkS")
		)
		(fp_line
			(start -0.7874 0.4064)
			(end -0.7874 -0.4064)
			(stroke
				(width 0.1524)
				(type default)
			)
			(layer "F.SilkS")
		)
		(fp_line
			(start 0.7874 -0.4064)
			(end 0.7874 0.4064)
			(stroke
				(width 0.1524)
				(type default)
			)
			(layer "F.SilkS")
		)
		(fp_line
			(start 0.7874 0.4064)
			(end -0.7874 0.4064)
			(stroke
				(width 0.1524)
				(type default)
			)
			(layer "F.SilkS")
		)
		(fp_line
			(start -0.67945 -0.305054)
			(end -0.12065 -0.305054)
			(stroke
				(width 0.1)
				(type default)
			)
			(layer "F.Fab")
		)
		(fp_line
			(start -0.67945 0.3048)
			(end -0.67945 -0.305054)
			(stroke
				(width 0.1)
				(type default)
			)
			(layer "F.Fab")
		)
		(fp_line
			(start -0.12065 -0.305054)
			(end -0.12065 -0.2794)
			(stroke
				(width 0.1)
				(type default)
			)
			(layer "F.Fab")
		)
		(fp_line
			(start -0.12065 -0.2794)
			(end 0.12065 -0.2794)
			(stroke
				(width 0.1)
				(type default)
			)
			(layer "F.Fab")
		)
		(fp_line
			(start -0.12065 0.2794)
			(end -0.12065 0.3048)
			(stroke
				(width 0.1)
				(type default)
			)
			(layer "F.Fab")
		)
		(fp_line
			(start -0.12065 0.3048)
			(end -0.67945 0.3048)
			(stroke
				(width 0.1)
				(type default)
			)
			(layer "F.Fab")
		)
		(fp_line
			(start 0.120396 0.2794)
			(end -0.12065 0.2794)
			(stroke
				(width 0.1)
				(type default)
			)
			(layer "F.Fab")
		)
		(fp_line
			(start 0.120396 0.3048)
			(end 0.120396 0.2794)
			(stroke
				(width 0.1)
				(type default)
			)
			(layer "F.Fab")
		)
		(fp_line
			(start 0.12065 -0.3048)
			(end 0.67945 -0.3048)
			(stroke
				(width 0.1)
				(type default)
			)
			(layer "F.Fab")
		)
		(fp_line
			(start 0.12065 -0.2794)
			(end 0.12065 -0.3048)
			(stroke
				(width 0.1)
				(type default)
			)
			(layer "F.Fab")
		)
		(fp_line
			(start 0.67945 -0.3048)
			(end 0.67945 0.3048)
			(stroke
				(width 0.1)
				(type default)
			)
			(layer "F.Fab")
		)
		(fp_line
			(start 0.67945 0.3048)
			(end 0.120396 0.3048)
			(stroke
				(width 0.1)
				(type default)
			)
			(layer "F.Fab")
		)
		(pad "1" smd circle
			(at -0.40005 0)
			(size 0 0)
			(layers "F.Cu" "F.Mask" "F.Paste")
			(net "RST_CPU1_RSMRST_N")
		)
		(pad "2" smd circle
			(at 0.40005 0)
			(size 0 0)
			(layers "F.Cu" "F.Mask" "F.Paste")
			(net "GND")
		)
	)
	(footprint ""
		(layer "F.Cu")
		(at 182.710836 -92.674948 -90)
		(property "Reference" "R6151"
			(at 0 0 270)
			(layer "F.SilkS")
			(hide yes)
			(effects
				(font
					(size 1.27 1.27)
				)
			)
		)
		(property "Value" ""
			(at 0 0 270)
			(layer "F.Fab")
			(effects
				(font
					(size 1.27 1.27)
				)
			)
		)
		(duplicate_pad_numbers_are_jumpers no)
		(fp_line
			(start -0.7874 0.4064)
			(end -0.7874 -0.4064)
			(stroke
				(width 0.1524)
				(type default)
			)
			(layer "F.SilkS")
		)
		(fp_line
			(start 0.7874 0.4064)
			(end -0.7874 0.4064)
			(stroke
				(width 0.1524)
				(type default)
			)
			(layer "F.SilkS")
		)
		(fp_line
			(start -0.7874 -0.4064)
			(end 0.7874 -0.4064)
			(stroke
				(width 0.1524)
				(type default)
			)
			(layer "F.SilkS")
		)
		(fp_line
			(start 0.7874 -0.4064)
			(end 0.7874 0.4064)
			(stroke
				(width 0.1524)
				(type default)
			)
			(layer "F.SilkS")
		)
		(fp_line
			(start -0.67945 0.3048)
			(end -0.67945 -0.305054)
			(stroke
				(width 0.1)
				(type default)
			)
			(layer "F.Fab")
		)
		(fp_line
			(start -0.12065 0.3048)
			(end -0.67945 0.3048)
			(stroke
				(width 0.1)
				(type default)
			)
			(layer "F.Fab")
		)
		(fp_line
			(start 0.120396 0.3048)
			(end 0.120396 0.2794)
			(stroke
				(width 0.1)
				(type default)
			)
			(layer "F.Fab")
		)
		(fp_line
			(start 0.67945 0.3048)
			(end 0.120396 0.3048)
			(stroke
				(width 0.1)
				(type default)
			)
			(layer "F.Fab")
		)
		(fp_line
			(start -0.12065 0.2794)
			(end -0.12065 0.3048)
			(stroke
				(width 0.1)
				(type default)
			)
			(layer "F.Fab")
		)
		(fp_line
			(start 0.120396 0.2794)
			(end -0.12065 0.2794)
			(stroke
				(width 0.1)
				(type default)
			)
			(layer "F.Fab")
		)
		(fp_line
			(start -0.12065 -0.2794)
			(end 0.12065 -0.2794)
			(stroke
				(width 0.1)
				(type default)
			)
			(layer "F.Fab")
		)
		(fp_line
			(start 0.12065 -0.2794)
			(end 0.12065 -0.3048)
			(stroke
				(width 0.1)
				(type default)
			)
			(layer "F.Fab")
		)
		(fp_line
			(start 0.12065 -0.3048)
			(end 0.67945 -0.3048)
			(stroke
				(width 0.1)
				(type default)
			)
			(layer "F.Fab")
		)
		(fp_line
			(start 0.67945 -0.3048)
			(end 0.67945 0.3048)
			(stroke
				(width 0.1)
				(type default)
			)
			(layer "F.Fab")
		)
		(fp_line
			(start -0.67945 -0.305054)
			(end -0.12065 -0.305054)
			(stroke
				(width 0.1)
				(type default)
			)
			(layer "F.Fab")
		)
		(fp_line
			(start -0.12065 -0.305054)
			(end -0.12065 -0.2794)
			(stroke
				(width 0.1)
				(type default)
			)
			(layer "F.Fab")
		)
		(pad "1" smd circle
			(at -0.40005 0 270)
			(size 0 0)
			(layers "F.Cu" "F.Mask" "F.Paste")
			(net "FAB_BMC_REV_ID0")
		)
		(pad "2" smd circle
			(at 0.40005 0 270)
			(size 0 0)
			(layers "F.Cu" "F.Mask" "F.Paste")
			(net "GND")
		)
	)
)
